# T6G (Grand Teton) — schematic netlist excerpt (pin names and nets, part order shuffled) for the footprints in the layout excerpt that follows; sources: Cadence DE-HDL packaged netlist, KiCad conversion of 04192023_DAF0TMB3IC0_F0TG_MB_C_brd_V02_OCP.brd

J27  SCONN288_DDR506112002KQ  IO  pkg DDR288S_1-1VXC  page 105
  VIN_BULK0  = P12V_MEM_CPU1
  RFU0  = NC
  VIN_MGMT  = P3V3_AUX
  HSCL  = I3C_SPD_DDRH_CPU1_SCL
  HSDA  = I3C_SPD_DDRH_CPU1_SDA
  VSS0  = GND
  DQ0_A  = M_H_CPU1_SA_DQ<0>
  VSS1  = GND
  DQ1_A  = M_H_CPU1_SA_DQ<1>
  VSS2  = GND
  DQS0_A_T  = M_H_CPU1_SA_DQS_DP<0>
  DQS0_A_C  = M_H_CPU1_SA_DQS_DN<0>
  VSS3  = GND
  DQ4_A  = M_H_CPU1_SA_DQ<4>
  VSS4  = GND
  DQ5_A  = M_H_CPU1_SA_DQ<5>
  VSS5  = GND
  DQ8_A  = M_H_CPU1_SA_DQ<8>
  VSS6  = GND
  DQ9_A  = M_H_CPU1_SA_DQ<9>
  VSS7  = GND
  DQS1_A_T  = M_H_CPU1_SA_DQS_DP<1>
  DQS1_A_C  = M_H_CPU1_SA_DQS_DN<1>
  VSS8  = GND
  DQ12_A  = M_H_CPU1_SA_DQ<12>
  VSS9  = GND
  DQ13_A  = M_H_CPU1_SA_DQ<13>
  VSS10  = GND
  DQ16_A  = M_H_CPU1_SA_DQ<16>
  VSS11  = GND
  DQ17_A  = M_H_CPU1_SA_DQ<17>
  VSS12  = GND
  DQS2_A_T  = M_H_CPU1_SA_DQS_DP<2>
  DQS2_A_C  = M_H_CPU1_SA_DQS_DN<2>
  VSS13  = GND
  DQ20_A  = M_H_CPU1_SA_DQ<20>
  VSS14  = GND
  DQ21_A  = M_H_CPU1_SA_DQ<21>
  VSS15  = GND
  DQ24_A  = M_H_CPU1_SA_DQ<24>
  VSS16  = GND
  DQ25_A  = M_H_CPU1_SA_DQ<25>
  VSS17  = GND
  DQS3_A_T  = M_H_CPU1_SA_DQS_DP<3>
  DQS3_A_C  = M_H_CPU1_SA_DQS_DN<3>
  VSS18  = GND
  DQ28_A  = M_H_CPU1_SA_DQ<28>
  VSS19  = GND
  DQ29_A  = M_H_CPU1_SA_DQ<29>
  VSS20  = GND
  CB0_A  = M_H_CPU1_SA_CB<0>
  VSS21  = GND
  CB1_A  = M_H_CPU1_SA_CB<1>
  VSS22  = GND
  DQS4_A_T  = M_H_CPU1_SA_DQS_DP<4>
  DQS4_A_C  = M_H_CPU1_SA_DQS_DN<4>
  VSS23  = GND
  CB4_A  = M_H_CPU1_SA_CB<4>
  VSS24  = GND
  CB5_A  = M_H_CPU1_SA_CB<5>
  VSS25  = GND
  ALERT_N  = M_H_CPU1_ALERT_N
  VSS26  = GND
  CS0_A_N  = M_H_CPU1_SA_CS_N<0>
  VSS27  = GND
  CA0_A  = M_H_CPU1_SA_CA<0>
  VSS28  = GND
  CA2_A  = M_H_CPU1_SA_CA<2>
  VSS29  = GND
  CA4_A  = M_H_CPU1_SA_CA<4>
  VSS30  = GND
  CA6_A  = M_H_CPU1_SA_CA<6>
  VSS31  = GND
  PAR_A  = M_H_CPU1_SA_PAR
  VSS32  = GND
  CA0_B  = M_H_CPU1_SB_CA<0>
  VSS33  = GND
  CA2_B  = M_H_CPU1_SB_CA<2>
  VSS34  = GND
  CA4_B  = M_H_CPU1_SB_CA<4>
  VSS35  = GND
  CA6_B  = M_H_CPU1_SB_CA<6>
  VSS36  = GND
  CS0_B_N  = M_H_CPU1_SB_CS_N<0>
  VSS37  = GND
  \lbd||rsp_a_n\  = M_H_CPU1_SA_RSP<0>
  \lbs||rsp_b_n\  = M_H_CPU1_SB_RSP<0>
  VSS38  = GND
  CB4_B  = M_H_CPU1_SB_CB<4>
  VSS39  = GND
  CB5_B  = M_H_CPU1_SB_CB<5>
  VSS40  = GND
  \dqs9_b_t||tdqs9_b_t||dbi4_b_n\  = M_H_CPU1_SB_DQS_DP<9>
  \dqs9_b_c||tdqs9_b_c\  = M_H_CPU1_SB_DQS_DN<9>
  VSS41  = GND
  CB0_B  = M_H_CPU1_SB_CB<0>
  VSS42  = GND
  CB1_B  = M_H_CPU1_SB_CB<1>
  VSS43  = GND
  DQ0_B  = M_H_CPU1_SB_DQ<0>
  VSS44  = GND
  DQ1_B  = M_H_CPU1_SB_DQ<1>
  VSS45  = GND
  DQS0_B_T  = M_H_CPU1_SB_DQS_DP<0>
  DQS0_B_C  = M_H_CPU1_SB_DQS_DN<0>
  VSS46  = GND
  DQ4_B  = M_H_CPU1_SB_DQ<4>
  VSS47  = GND
  DQ5_B  = M_H_CPU1_SB_DQ<5>
  VSS48  = GND
  DQ8_B  = M_H_CPU1_SB_DQ<8>
  VSS49  = GND
  DQ9_B  = M_H_CPU1_SB_DQ<9>
  VSS50  = GND
  DQS1_B_T  = M_H_CPU1_SB_DQS_DP<1>
  DQS1_B_C  = M_H_CPU1_SB_DQS_DN<1>
  VSS51  = GND
  DQ12_B  = M_H_CPU1_SB_DQ<12>
  VSS52  = GND
  DQ13_B  = M_H_CPU1_SB_DQ<13>
  VSS53  = GND
  DQ16_B  = M_H_CPU1_SB_DQ<16>
  VSS54  = GND
  DQ17_B  = M_H_CPU1_SB_DQ<17>
  VSS55  = GND
  DQS2_B_T  = M_H_CPU1_SB_DQS_DP<2>
  DQS2_B_C  = M_H_CPU1_SB_DQS_DN<2>
  VSS56  = GND
  DQ20_B  = M_H_CPU1_SB_DQ<20>
  VSS57  = GND
  DQ21_B  = M_H_CPU1_SB_DQ<21>
  VSS58  = GND
  DQ24_B  = M_H_CPU1_SB_DQ<24>
  VSS59  = GND
  DQ25_B  = M_H_CPU1_SB_DQ<25>
  VSS60  = GND
  DQS3_B_T  = M_H_CPU1_SB_DQS_DP<3>
  DQS3_B_C  = M_H_CPU1_SB_DQS_DN<3>
  VSS61  = GND
  DQ28_B  = M_H_CPU1_SB_DQ<28>
  VSS62  = GND
  DQ29_B  = M_H_CPU1_SB_DQ<29>
  VSS63  = GND
  RFU1  = NC
  VIN_BULK1  = P12V_MEM_CPU1
  VIN_BULK2  = P12V_MEM_CPU1
  \pwr_good||fail_n\  = PWRGD_CHH_CPU1_DIMM
  HAS  = PD_CHH_CPU1_DIMM_SAA
  RFU2  = NC
  RFU3  = NC
  VSS64  = GND
  DQ2_A  = M_H_CPU1_SA_DQ<2>
  VSS65  = GND
  DQ3_A  = M_H_CPU1_SA_DQ<3>
  VSS66  = GND
  \dqs5_a_c||tdqs5_a_c||dqs5_a_t||tdqs5_a_t\  = M_H_CPU1_SA_DQS_DN<5>
  \dqs5_a_t||tdqs5_a_t\  = M_H_CPU1_SA_DQS_DP<5>
  VSS67  = GND
  DQ6_A  = M_H_CPU1_SA_DQ<6>
  VSS68  = GND
  DQ7_A  = M_H_CPU1_SA_DQ<7>
  VSS69  = GND
  DQ10_A  = M_H_CPU1_SA_DQ<10>
  VSS70  = GND
  DQ11_A  = M_H_CPU1_SA_DQ<11>
  VSS71  = GND
  \dqs6_a_c||tdqs6_a_c||dqs6_a_t||tdqs6_a_t\  = M_H_CPU1_SA_DQS_DN<6>
  \dqs6_a_t||tdqs6_a_t\  = M_H_CPU1_SA_DQS_DP<6>
  VSS72  = GND
  DQ14_A  = M_H_CPU1_SA_DQ<14>
  VSS73  = GND
  DQ15_A  = M_H_CPU1_SA_DQ<15>
  VSS74  = GND
  DQ18_A  = M_H_CPU1_SA_DQ<18>
  VSS75  = GND
  DQ19_A  = M_H_CPU1_SA_DQ<19>
  VSS76  = GND
  \dqs7_a_c||tdqs7_a_c\  = M_H_CPU1_SA_DQS_DN<7>
  \dqs7_a_t||tdqs7_a_t\  = M_H_CPU1_SA_DQS_DP<7>
  VSS77  = GND
  DQ22_A  = M_H_CPU1_SA_DQ<22>
  VSS78  = GND
  DQ23_A  = M_H_CPU1_SA_DQ<23>
  VSS79  = GND
  DQ26_A  = M_H_CPU1_SA_DQ<26>
  VSS80  = GND
  DQ27_A  = M_H_CPU1_SA_DQ<27>
  VSS81  = GND
  \dqs8_a_c||tdqs8_a_c\  = M_H_CPU1_SA_DQS_DN<8>
  \dqs8_a_t||tdqs8_a_t\  = M_H_CPU1_SA_DQS_DP<8>
  VSS82  = GND
  DQ30_A  = M_H_CPU1_SA_DQ<30>
  VSS83  = GND
  DQ31_A  = M_H_CPU1_SA_DQ<31>
  VSS84  = GND
  CB2_A  = M_H_CPU1_SA_CB<2>
  VSS85  = GND
  CB3_A  = M_H_CPU1_SA_CB<3>
  VSS86  = GND
  \dqs9_a_c||tdqs9_a_c\  = M_H_CPU1_SA_DQS_DN<9>
  \dqs9_a_t||tdqs9_a_t\  = M_H_CPU1_SA_DQS_DP<9>
  VSS87  = GND
  CB6_A  = M_H_CPU1_SA_CB<6>
  VSS88  = GND
  CB7_A  = M_H_CPU1_SA_CB<7>
  VSS89  = GND
  RESET_N  = M_H_CPU1_RESET_N
  VSS90  = GND
  CS1_A_N  = M_H_CPU1_SA_CS_N<1>
  VSS91  = GND
  CA1_A  = M_H_CPU1_SA_CA<1>
  VSS92  = GND
  CA3_A  = M_H_CPU1_SA_CA<3>
  VSS93  = GND
  CA5_A  = M_H_CPU1_SA_CA<5>
  VSS94  = GND
  CK_T  = M_H_CPU1_CLK_DP<0>
  CK_C  = M_H_CPU1_CLK_DN<0>
  VSS95  = GND
  RFU4  = NC
  CA1_B  = M_H_CPU1_SB_CA<1>
  VSS96  = GND
  CA3_B  = M_H_CPU1_SB_CA<3>
  VSS97  = GND
  CA5_B  = M_H_CPU1_SB_CA<5>
  VSS98  = GND
  PAR_B  = M_H_CPU1_SB_PAR
  VSS99  = GND
  CS1_B_N  = M_H_CPU1_SB_CS_N<1>
  VSS100  = GND
  RFU5  = NC
  RFU6  = NC
  VSS101  = GND
  CB6_B  = M_H_CPU1_SB_CB<6>
  VSS102  = GND
  CB7_B  = M_H_CPU1_SB_CB<7>
  VSS103  = GND
  DQS4_B_C  = M_H_CPU1_SB_DQS_DN<4>
  DQS4_B_T  = M_H_CPU1_SB_DQS_DP<4>
  VSS104  = GND
  CB2_B  = M_H_CPU1_SB_CB<2>
  VSS105  = GND
  CB3_B  = M_H_CPU1_SB_CB<3>
  VSS106  = GND
  DQ2_B  = M_H_CPU1_SB_DQ<2>
  VSS107  = GND
  DQ3_B  = M_H_CPU1_SB_DQ<3>
  VSS108  = GND
  \dqs5_b_c||tdqs5_b_c\  = M_H_CPU1_SB_DQS_DN<5>
  \dqs5_b_t||tdqs5_b_t\  = M_H_CPU1_SB_DQS_DP<5>
  VSS109  = GND
  DQ6_B  = M_H_CPU1_SB_DQ<6>
  VSS110  = GND
  DQ7_B  = M_H_CPU1_SB_DQ<7>
  VSS111  = GND
  DQ10_B  = M_H_CPU1_SB_DQ<10>
  VSS112  = GND
  DQ11_B  = M_H_CPU1_SB_DQ<11>
  VSS113  = GND
  \dqs6_b_c||tdqs6_b_c\  = M_H_CPU1_SB_DQS_DN<6>
  \dqs6_b_t||tdqs6_b_t\  = M_H_CPU1_SB_DQS_DP<6>
  VSS114  = GND
  DQ14_B  = M_H_CPU1_SB_DQ<14>
  VSS115  = GND
  DQ15_B  = M_H_CPU1_SB_DQ<15>
  VSS116  = GND
  DQ18_B  = M_H_CPU1_SB_DQ<18>
  VSS117  = GND
  DQ19_B  = M_H_CPU1_SB_DQ<19>
  VSS118  = GND
  \dqs7_b_c||tdqs7_b_c\  = M_H_CPU1_SB_DQS_DN<7>
  \dqs7_b_t||tdqs7_b_t\  = M_H_CPU1_SB_DQS_DP<7>
  VSS119  = GND
  DQ22_B  = M_H_CPU1_SB_DQ<22>
  VSS120  = GND
  DQ23_B  = M_H_CPU1_SB_DQ<23>
  VSS121  = GND
  DQ26_B  = M_H_CPU1_SB_DQ<26>
  VSS122  = GND
  DQ27_B  = M_H_CPU1_SB_DQ<27>
  VSS123  = GND
  \dqs8_b_c||tdqs8_b_c\  = M_H_CPU1_SB_DQS_DN<8>
  \dqs8_b_t||tdqs8_b_t\  = M_H_CPU1_SB_DQS_DP<8>
  VSS124  = GND
  DQ30_B  = M_H_CPU1_SB_DQ<30>
  VSS125  = GND
  DQ31_B  = M_H_CPU1_SB_DQ<31>
  VSS126  = GND
  G1  = GND
  G2  = GND
  G3  = GND

(kicad_pcb
	(version 20260206)
	(generator "pcbnew")
	(generator_version "10.0")
	(general
		(thickness 1.6)
		(legacy_teardrops no)
	)
	(paper "A4")
	(title_block
		(title "04192023_DAF0TMB3IC0_F0TG_MB_C_brd_V02_OCP.brd")
		(comment 1 "Grand Teton / footprint 583 of 8354 (J27), pads 277-291 of 291")
	)
	(layers
		(0 "F.Cu" signal "TOP")
		(4 "In1.Cu" signal "GND")
		(6 "In2.Cu" signal "IN1")
		(8 "In3.Cu" signal "GND1")
		(10 "In4.Cu" signal "IN2")
		(12 "In5.Cu" signal "GND2")
		(14 "In6.Cu" signal "IN3")
		(16 "In7.Cu" signal "GND3")
		(18 "In8.Cu" signal "VCC")
		(20 "In9.Cu" signal "VCC1")
		(22 "In10.Cu" signal "GND4")
		(24 "In11.Cu" signal "IN4")
		(26 "In12.Cu" signal "GND5")
		(28 "In13.Cu" signal "IN5")
		(30 "In14.Cu" signal "GND6")
		(32 "In15.Cu" signal "IN6")
		(34 "In16.Cu" signal "GND7")
		(2 "B.Cu" signal "BOTTOM")
		(9 "F.Adhes" user "F.Adhesive")
		(11 "B.Adhes" user "B.Adhesive")
		(13 "F.Paste" user "Package Geometry/Pastemask Top")
		(15 "B.Paste" user "Package Geometry/Pastemask Bottom")
		(5 "F.SilkS" user "Ref Des/Silkscreen Top")
		(7 "B.SilkS" user "Ref Des/Silkscreen Bottom")
		(1 "F.Mask" user "Board Geometry/Soldermask Top")
		(3 "B.Mask" user "Board Geometry/Soldermask Bottom")
		(17 "Dwgs.User" user "User.Drawings")
		(19 "Cmts.User" user "User.Comments")
		(21 "Eco1.User" user "User.Eco1")
		(23 "Eco2.User" user "User.Eco2")
		(25 "Edge.Cuts" user "Board Geometry/Outline")
		(27 "Margin" user)
		(31 "F.CrtYd" user "Package Geometry/Place Bound Top")
		(29 "B.CrtYd" user "Package Geometry/Place Bound Bottom")
		(35 "F.Fab" user "Ref Des/Assembly Top")
		(33 "B.Fab" user "Ref Des/Assembly Bottom")
	)
	(footprint ""
		(layer "F.Cu")
		(at 174.022004 -255.560322 180)
		(property "Reference" "J27"
			(at -2.7178 -81.857088 0)
			(unlocked yes)
			(layer "F.SilkS")
			(effects
				(font
					(size 0.7874 0.5842)
					(thickness 0.1524)
				)
			)
		)
		(property "Value" ""
			(at 0 0 180)
			(layer "F.Fab")
			(effects
				(font
					(size 1.27 1.27)
				)
			)
		)
		(duplicate_pad_numbers_are_jumpers no)
		(pad "277" smd rect
			(at 2.050034 53.975 90)
			(size 0.519938 1.4986)
			(layers "F.Cu" "F.Mask" "F.Paste")
			(net "GND")
		)
		(pad "278" smd rect
			(at 2.050034 54.824884 90)
			(size 0.519938 1.4986)
			(layers "F.Cu" "F.Mask" "F.Paste")
			(net "M_H_CPU1_SB_DQ<26>")
		)
		(pad "279" smd rect
			(at 2.050034 55.675022 90)
			(size 0.519938 1.4986)
			(layers "F.Cu" "F.Mask" "F.Paste")
			(net "GND")
		)
		(pad "280" smd rect
			(at 2.050034 56.524906 90)
			(size 0.519938 1.4986)
			(layers "F.Cu" "F.Mask" "F.Paste")
			(net "M_H_CPU1_SB_DQ<27>")
		)
		(pad "281" smd rect
			(at 2.050034 57.375044 90)
			(size 0.519938 1.4986)
			(layers "F.Cu" "F.Mask" "F.Paste")
			(net "GND")
		)
		(pad "282" smd rect
			(at 2.050034 58.224928 90)
			(size 0.519938 1.4986)
			(layers "F.Cu" "F.Mask" "F.Paste")
			(net "M_H_CPU1_SB_DQS_DN<8>")
		)
		(pad "283" smd rect
			(at 2.050034 59.075066 90)
			(size 0.519938 1.4986)
			(layers "F.Cu" "F.Mask" "F.Paste")
			(net "M_H_CPU1_SB_DQS_DP<8>")
		)
		(pad "284" smd rect
			(at 2.050034 59.92495 90)
			(size 0.519938 1.4986)
			(layers "F.Cu" "F.Mask" "F.Paste")
			(net "GND")
		)
		(pad "285" smd rect
			(at 2.050034 60.775088 90)
			(size 0.519938 1.4986)
			(layers "F.Cu" "F.Mask" "F.Paste")
			(net "M_H_CPU1_SB_DQ<30>")
		)
		(pad "286" smd rect
			(at 2.050034 61.624972 90)
			(size 0.519938 1.4986)
			(layers "F.Cu" "F.Mask" "F.Paste")
			(net "GND")
		)
		(pad "287" smd rect
			(at 2.050034 62.47511 90)
			(size 0.519938 1.4986)
			(layers "F.Cu" "F.Mask" "F.Paste")
			(net "M_H_CPU1_SB_DQ<31>")
		)
		(pad "288" smd rect
			(at 2.050034 63.324994 90)
			(size 0.519938 1.4986)
			(layers "F.Cu" "F.Mask" "F.Paste")
			(net "GND")
		)
		(pad "G1" thru_hole oval
			(at 0 -68.97497 90)
			(size 1.7272 3.4798)
			(drill oval 1.2192 2.4638)
			(layers "*.Cu" "*.Mask")
			(remove_unused_layers no)
			(net "GND")
			(clearance 0.127)
			(thermal_gap 0.127)
		)
		(pad "G2" thru_hole oval
			(at 0 3.875024 90)
			(size 1.7272 3.4798)
			(drill oval 1.2192 2.4638)
			(layers "*.Cu" "*.Mask")
			(remove_unused_layers no)
			(net "GND")
			(clearance 0.127)
			(thermal_gap 0.127)
		)
		(pad "G3" thru_hole oval
			(at 0 68.97497 90)
			(size 1.7272 3.4798)
			(drill oval 1.2192 2.4638)
			(layers "*.Cu" "*.Mask")
			(remove_unused_layers no)
			(net "GND")
			(clearance 0.127)
			(thermal_gap 0.127)
		)
	)
)
